(kicad_pcb
	(version 20260206)
	(generator "pcbnew")
	(generator_version "10.0")
	(general
		(thickness 1.6)
		(legacy_teardrops no)
	)
	(paper "A4")
	(title_block
		(title "12092022_DA0F0TMDCD0_F0T_Management_Board_D_brd_V3_OCP.brd")
		(comment 1 "Grand Teton / footprints 1339-1344 of 1440")
	)
	(layers
		(0 "F.Cu" signal "TOP")
		(4 "In1.Cu" signal "GND")
		(6 "In2.Cu" signal "IN1")
		(8 "In3.Cu" signal "GND1")
		(10 "In4.Cu" signal "IN2")
		(12 "In5.Cu" signal "VCC")
		(14 "In6.Cu" signal "VCC1")
		(16 "In7.Cu" signal "IN3")
		(18 "In8.Cu" signal "GND2")
		(20 "In9.Cu" signal "IN4")
		(22 "In10.Cu" signal "GND3")
		(2 "B.Cu" signal "BOTTOM")
		(9 "F.Adhes" user "F.Adhesive")
		(11 "B.Adhes" user "B.Adhesive")
		(13 "F.Paste" user "Package Geometry/Pastemask Top")
		(15 "B.Paste" user "Package Geometry/Pastemask Bottom")
		(5 "F.SilkS" user "Ref Des/Silkscreen Top")
		(7 "B.SilkS" user "Ref Des/Silkscreen Bottom")
		(1 "F.Mask" user "Board Geometry/Soldermask Top")
		(3 "B.Mask" user "Board Geometry/Soldermask Bottom")
		(17 "Dwgs.User" user "User.Drawings")
		(19 "Cmts.User" user "User.Comments")
		(21 "Eco1.User" user "User.Eco1")
		(23 "Eco2.User" user "User.Eco2")
		(25 "Edge.Cuts" user "Board Geometry/Outline")
		(27 "Margin" user)
		(31 "F.CrtYd" user "Package Geometry/Place Bound Top")
		(29 "B.CrtYd" user "Package Geometry/Place Bound Bottom")
		(35 "F.Fab" user "Ref Des/Assembly Top")
		(33 "B.Fab" user "Ref Des/Assembly Bottom")
	)
	(footprint ""
		(layer "B.Cu")
		(at -14.224 -100.584 180)
		(property "Reference" "DB2"
			(at 1.7018 -5.74167 0)
			(unlocked yes)
			(layer "B.SilkS")
			(effects
				(font
					(size 0.7874 0.5842)
					(thickness 0.1524)
				)
				(justify left mirror)
			)
		)
		(property "Value" ""
			(at 0 0 0)
			(layer "B.Fab")
			(effects
				(font
					(size 1.27 1.27)
				)
				(justify mirror)
			)
		)
		(duplicate_pad_numbers_are_jumpers no)
		(fp_line
			(start 3.330702 -4.771136)
			(end -3.330702 -4.771136)
			(stroke
				(width 0.1524)
				(type default)
			)
			(layer "B.SilkS")
		)
		(fp_line
			(start 0 4.011168)
			(end 3.330702 -4.771136)
			(stroke
				(width 0.1524)
				(type default)
			)
			(layer "B.SilkS")
		)
		(fp_line
			(start -3.330702 -4.771136)
			(end 0 4.011168)
			(stroke
				(width 0.1524)
				(type default)
			)
			(layer "B.SilkS")
		)
		(fp_line
			(start 3.330702 -4.771136)
			(end -3.330702 -4.771136)
			(stroke
				(width 0.1)
				(type default)
			)
			(layer "B.Fab")
		)
		(fp_line
			(start 0 4.011168)
			(end 3.330702 -4.771136)
			(stroke
				(width 0.1)
				(type default)
			)
			(layer "B.Fab")
		)
		(fp_line
			(start -3.330702 -4.771136)
			(end 0 4.011168)
			(stroke
				(width 0.1)
				(type default)
			)
			(layer "B.Fab")
		)
		(pad "1" thru_hole circle
			(at 0 0)
			(size 2.159 2.159)
			(drill 1.7018)
			(layers "*.Cu" "*.Mask")
			(remove_unused_layers no)
			(net "T_GND")
			(clearance 0.0254)
			(thermal_gap 0.0254)
		)
		(pad "2" thru_hole circle
			(at 1.27 -3.348736)
			(size 2.159 2.159)
			(drill 1.7018)
			(layers "*.Cu" "*.Mask")
			(remove_unused_layers no)
			(net "TDR_SE_50_OHM_IN1")
			(clearance 0.0254)
			(thermal_gap 0.0254)
		)
		(pad "3" thru_hole circle
			(at -1.27 -3.348736)
			(size 2.159 2.159)
			(drill 1.7018)
			(layers "*.Cu" "*.Mask")
			(remove_unused_layers no)
			(net "TDR_SE_50_OHM_IN1")
			(clearance 0.0254)
			(thermal_gap 0.0254)
		)
	)
	(footprint ""
		(layer "B.Cu")
		(at 58.547 -21.082 -90)
		(property "Reference" "U29"
			(at 1.2065 1.94437 270)
			(unlocked yes)
			(layer "B.SilkS")
			(effects
				(font
					(size 0.7874 0.5842)
					(thickness 0.1524)
				)
				(justify left mirror)
			)
		)
		(property "Value" ""
			(at 0 0 90)
			(layer "B.Fab")
			(effects
				(font
					(size 1.27 1.27)
				)
				(justify mirror)
			)
		)
		(duplicate_pad_numbers_are_jumpers no)
		(fp_line
			(start -1.3462 1.1938)
			(end -1.3462 -1.1938)
			(stroke
				(width 0.1524)
				(type default)
			)
			(layer "B.SilkS")
		)
		(fp_line
			(start 1.3462 1.1938)
			(end -1.3462 1.1938)
			(stroke
				(width 0.1524)
				(type default)
			)
			(layer "B.SilkS")
		)
		(fp_line
			(start -1.3462 -1.1938)
			(end 1.3462 -1.1938)
			(stroke
				(width 0.1524)
				(type default)
			)
			(layer "B.SilkS")
		)
		(fp_line
			(start 1.3462 -1.1938)
			(end 1.3462 1.1684)
			(stroke
				(width 0.1524)
				(type default)
			)
			(layer "B.SilkS")
		)
		(fp_poly
			(pts
				(xy 1.447038 -0.760476) (xy 2.052066 -0.457962) (xy 2.052066 -1.06299)
			)
			(stroke
				(width 0)
				(type default)
			)
			(fill yes)
			(layer "B.SilkS")
		)
		(fp_line
			(start -0.674878 1.124966)
			(end -0.674878 -1.124966)
			(stroke
				(width 0.1)
				(type default)
			)
			(layer "B.Fab")
		)
		(fp_line
			(start 0.674878 1.124966)
			(end -0.674878 1.124966)
			(stroke
				(width 0.1)
				(type default)
			)
			(layer "B.Fab")
		)
		(fp_line
			(start -0.674878 -1.124966)
			(end 0.674878 -1.124966)
			(stroke
				(width 0.1)
				(type default)
			)
			(layer "B.Fab")
		)
		(fp_line
			(start 0.674878 -1.124966)
			(end 0.674878 1.124966)
			(stroke
				(width 0.1)
				(type default)
			)
			(layer "B.Fab")
		)
		(fp_poly
			(pts
				(xy 1.447038 -0.760476) (xy 2.052066 -0.457962) (xy 2.052066 -1.06299)
			)
			(stroke
				(width 0)
				(type default)
			)
			(fill yes)
			(layer "B.Fab")
		)
		(pad "1" smd rect
			(at 0.899922 -0.750062 90)
			(size 0.6096 0.6096)
			(layers "B.Cu" "B.Mask" "B.Paste")
			(net "DEBUG_PORT_PRSNT")
		)
		(pad "2" smd rect
			(at 0.899922 0)
			(size 0.4064 0.6096)
			(layers "B.Cu" "B.Mask" "B.Paste")
			(net "SPA_SOUT_SW_DBG")
		)
		(pad "3" smd rect
			(at 0.899922 0.750062 90)
			(size 0.6096 0.6096)
			(layers "B.Cu" "B.Mask" "B.Paste")
			(net "GND")
		)
		(pad "4" smd rect
			(at -0.899922 0.750062 90)
			(size 0.6096 0.6096)
			(layers "B.Cu" "B.Mask" "B.Paste")
			(net "DEBUG_PORT_UART_TX")
		)
		(pad "5" smd rect
			(at -0.899922 -0.750062 90)
			(size 0.6096 0.6096)
			(layers "B.Cu" "B.Mask" "B.Paste")
			(net "P3V3_AUX")
		)
	)
	(footprint ""
		(layer "B.Cu")
		(at 65.108582 -30.867604 -90)
		(property "Reference" "R523"
			(at 0 0 90)
			(layer "B.SilkS")
			(hide yes)
			(effects
				(font
					(size 1.27 1.27)
				)
				(justify mirror)
			)
		)
		(property "Value" ""
			(at 0 0 90)
			(layer "B.Fab")
			(effects
				(font
					(size 1.27 1.27)
				)
				(justify mirror)
			)
		)
		(duplicate_pad_numbers_are_jumpers no)
		(fp_line
			(start -0.7874 0.4064)
			(end 0.7874 0.4064)
			(stroke
				(width 0.1524)
				(type default)
			)
			(layer "B.SilkS")
		)
		(fp_line
			(start 0.7874 0.4064)
			(end 0.7874 -0.4064)
			(stroke
				(width 0.1524)
				(type default)
			)
			(layer "B.SilkS")
		)
		(fp_line
			(start -0.7874 -0.4064)
			(end -0.7874 0.4064)
			(stroke
				(width 0.1524)
				(type default)
			)
			(layer "B.SilkS")
		)
		(fp_line
			(start 0.7874 -0.4064)
			(end -0.7874 -0.4064)
			(stroke
				(width 0.1524)
				(type default)
			)
			(layer "B.SilkS")
		)
		(fp_line
			(start -0.67945 0.3048)
			(end -0.120396 0.3048)
			(stroke
				(width 0.1)
				(type default)
			)
			(layer "B.Fab")
		)
		(fp_line
			(start -0.120396 0.3048)
			(end -0.120396 0.2794)
			(stroke
				(width 0.1)
				(type default)
			)
			(layer "B.Fab")
		)
		(fp_line
			(start 0.12065 0.3048)
			(end 0.67945 0.3048)
			(stroke
				(width 0.1)
				(type default)
			)
			(layer "B.Fab")
		)
		(fp_line
			(start 0.67945 0.3048)
			(end 0.67945 -0.305054)
			(stroke
				(width 0.1)
				(type default)
			)
			(layer "B.Fab")
		)
		(fp_line
			(start -0.120396 0.2794)
			(end 0.12065 0.2794)
			(stroke
				(width 0.1)
				(type default)
			)
			(layer "B.Fab")
		)
		(fp_line
			(start 0.12065 0.2794)
			(end 0.12065 0.3048)
			(stroke
				(width 0.1)
				(type default)
			)
			(layer "B.Fab")
		)
		(fp_line
			(start -0.12065 -0.2794)
			(end -0.12065 -0.3048)
			(stroke
				(width 0.1)
				(type default)
			)
			(layer "B.Fab")
		)
		(fp_line
			(start 0.12065 -0.2794)
			(end -0.12065 -0.2794)
			(stroke
				(width 0.1)
				(type default)
			)
			(layer "B.Fab")
		)
		(fp_line
			(start -0.67945 -0.3048)
			(end -0.67945 0.3048)
			(stroke
				(width 0.1)
				(type default)
			)
			(layer "B.Fab")
		)
		(fp_line
			(start -0.12065 -0.3048)
			(end -0.67945 -0.3048)
			(stroke
				(width 0.1)
				(type default)
			)
			(layer "B.Fab")
		)
		(fp_line
			(start 0.12065 -0.305054)
			(end 0.12065 -0.2794)
			(stroke
				(width 0.1)
				(type default)
			)
			(layer "B.Fab")
		)
		(fp_line
			(start 0.67945 -0.305054)
			(end 0.12065 -0.305054)
			(stroke
				(width 0.1)
				(type default)
			)
			(layer "B.Fab")
		)
		(pad "1" smd circle
			(at 0.40005 0 90)
			(size 0 0)
			(layers "B.Cu" "B.Mask" "B.Paste")
			(net "P3V3_RGM")
		)
		(pad "2" smd circle
			(at -0.40005 0 90)
			(size 0 0)
			(layers "B.Cu" "B.Mask" "B.Paste")
			(net "JTAG_SCM_TDO")
		)
	)
	(footprint ""
		(layer "B.Cu")
		(at 66.0908 -34.63798 90)
		(property "Reference" "R759"
			(at 0 0 90)
			(layer "B.SilkS")
			(hide yes)
			(effects
				(font
					(size 1.27 1.27)
				)
				(justify mirror)
			)
		)
		(property "Value" ""
			(at 0 0 90)
			(layer "B.Fab")
			(effects
				(font
					(size 1.27 1.27)
				)
				(justify mirror)
			)
		)
		(duplicate_pad_numbers_are_jumpers no)
		(fp_line
			(start 0.7874 -0.4064)
			(end -0.7874 -0.4064)
			(stroke
				(width 0.1524)
				(type default)
			)
			(layer "B.SilkS")
		)
		(fp_line
			(start -0.7874 -0.4064)
			(end -0.7874 0.4064)
			(stroke
				(width 0.1524)
				(type default)
			)
			(layer "B.SilkS")
		)
		(fp_line
			(start 0.7874 0.4064)
			(end 0.7874 -0.4064)
			(stroke
				(width 0.1524)
				(type default)
			)
			(layer "B.SilkS")
		)
		(fp_line
			(start -0.7874 0.4064)
			(end 0.7874 0.4064)
			(stroke
				(width 0.1524)
				(type default)
			)
			(layer "B.SilkS")
		)
		(fp_line
			(start 0.67945 -0.305054)
			(end 0.12065 -0.305054)
			(stroke
				(width 0.1)
				(type default)
			)
			(layer "B.Fab")
		)
		(fp_line
			(start 0.12065 -0.305054)
			(end 0.12065 -0.2794)
			(stroke
				(width 0.1)
				(type default)
			)
			(layer "B.Fab")
		)
		(fp_line
			(start -0.12065 -0.3048)
			(end -0.67945 -0.3048)
			(stroke
				(width 0.1)
				(type default)
			)
			(layer "B.Fab")
		)
		(fp_line
			(start -0.67945 -0.3048)
			(end -0.67945 0.3048)
			(stroke
				(width 0.1)
				(type default)
			)
			(layer "B.Fab")
		)
		(fp_line
			(start 0.12065 -0.2794)
			(end -0.12065 -0.2794)
			(stroke
				(width 0.1)
				(type default)
			)
			(layer "B.Fab")
		)
		(fp_line
			(start -0.12065 -0.2794)
			(end -0.12065 -0.3048)
			(stroke
				(width 0.1)
				(type default)
			)
			(layer "B.Fab")
		)
		(fp_line
			(start 0.12065 0.2794)
			(end 0.12065 0.3048)
			(stroke
				(width 0.1)
				(type default)
			)
			(layer "B.Fab")
		)
		(fp_line
			(start -0.120396 0.2794)
			(end 0.12065 0.2794)
			(stroke
				(width 0.1)
				(type default)
			)
			(layer "B.Fab")
		)
		(fp_line
			(start 0.67945 0.3048)
			(end 0.67945 -0.305054)
			(stroke
				(width 0.1)
				(type default)
			)
			(layer "B.Fab")
		)
		(fp_line
			(start 0.12065 0.3048)
			(end 0.67945 0.3048)
			(stroke
				(width 0.1)
				(type default)
			)
			(layer "B.Fab")
		)
		(fp_line
			(start -0.120396 0.3048)
			(end -0.120396 0.2794)
			(stroke
				(width 0.1)
				(type default)
			)
			(layer "B.Fab")
		)
		(fp_line
			(start -0.67945 0.3048)
			(end -0.120396 0.3048)
			(stroke
				(width 0.1)
				(type default)
			)
			(layer "B.Fab")
		)
		(pad "1" smd circle
			(at 0.40005 0 270)
			(size 0 0)
			(layers "B.Cu" "B.Mask" "B.Paste")
			(net "UART_BMC_5_RXD")
		)
		(pad "2" smd circle
			(at -0.40005 0 270)
			(size 0 0)
			(layers "B.Cu" "B.Mask" "B.Paste")
			(net "UART_BMC_5_RXD_R")
		)
	)
	(footprint ""
		(layer "B.Cu")
		(at 37.084 -106.3625 -90)
		(property "Reference" "R226"
			(at 0 0 90)
			(layer "B.SilkS")
			(hide yes)
			(effects
				(font
					(size 1.27 1.27)
				)
				(justify mirror)
			)
		)
		(property "Value" ""
			(at 0 0 90)
			(layer "B.Fab")
			(effects
				(font
					(size 1.27 1.27)
				)
				(justify mirror)
			)
		)
		(duplicate_pad_numbers_are_jumpers no)
		(fp_line
			(start -0.7874 0.4064)
			(end 0.7874 0.4064)
			(stroke
				(width 0.1524)
				(type default)
			)
			(layer "B.SilkS")
		)
		(fp_line
			(start 0.7874 0.4064)
			(end 0.7874 -0.4064)
			(stroke
				(width 0.1524)
				(type default)
			)
			(layer "B.SilkS")
		)
		(fp_line
			(start -0.7874 -0.4064)
			(end -0.7874 0.4064)
			(stroke
				(width 0.1524)
				(type default)
			)
			(layer "B.SilkS")
		)
		(fp_line
			(start 0.7874 -0.4064)
			(end -0.7874 -0.4064)
			(stroke
				(width 0.1524)
				(type default)
			)
			(layer "B.SilkS")
		)
		(fp_line
			(start -0.67945 0.3048)
			(end -0.120396 0.3048)
			(stroke
				(width 0.1)
				(type default)
			)
			(layer "B.Fab")
		)
		(fp_line
			(start -0.120396 0.3048)
			(end -0.120396 0.2794)
			(stroke
				(width 0.1)
				(type default)
			)
			(layer "B.Fab")
		)
		(fp_line
			(start 0.12065 0.3048)
			(end 0.67945 0.3048)
			(stroke
				(width 0.1)
				(type default)
			)
			(layer "B.Fab")
		)
		(fp_line
			(start 0.67945 0.3048)
			(end 0.67945 -0.305054)
			(stroke
				(width 0.1)
				(type default)
			)
			(layer "B.Fab")
		)
		(fp_line
			(start -0.120396 0.2794)
			(end 0.12065 0.2794)
			(stroke
				(width 0.1)
				(type default)
			)
			(layer "B.Fab")
		)
		(fp_line
			(start 0.12065 0.2794)
			(end 0.12065 0.3048)
			(stroke
				(width 0.1)
				(type default)
			)
			(layer "B.Fab")
		)
		(fp_line
			(start -0.12065 -0.2794)
			(end -0.12065 -0.3048)
			(stroke
				(width 0.1)
				(type default)
			)
			(layer "B.Fab")
		)
		(fp_line
			(start 0.12065 -0.2794)
			(end -0.12065 -0.2794)
			(stroke
				(width 0.1)
				(type default)
			)
			(layer "B.Fab")
		)
		(fp_line
			(start -0.67945 -0.3048)
			(end -0.67945 0.3048)
			(stroke
				(width 0.1)
				(type default)
			)
			(layer "B.Fab")
		)
		(fp_line
			(start -0.12065 -0.3048)
			(end -0.67945 -0.3048)
			(stroke
				(width 0.1)
				(type default)
			)
			(layer "B.Fab")
		)
		(fp_line
			(start 0.12065 -0.305054)
			(end 0.12065 -0.2794)
			(stroke
				(width 0.1)
				(type default)
			)
			(layer "B.Fab")
		)
		(fp_line
			(start 0.67945 -0.305054)
			(end 0.12065 -0.305054)
			(stroke
				(width 0.1)
				(type default)
			)
			(layer "B.Fab")
		)
		(pad "1" smd circle
			(at 0.40005 0 90)
			(size 0 0)
			(layers "B.Cu" "B.Mask" "B.Paste")
			(net "P3V3_AUX")
		)
		(pad "2" smd circle
			(at -0.40005 0 90)
			(size 0 0)
			(layers "B.Cu" "B.Mask" "B.Paste")
			(net "JTAG_MB_TDI")
		)
	)
	(footprint ""
		(layer "B.Cu")
		(at 83.16722 -43.538394 180)
		(property "Reference" "R9"
			(at 0 0 0)
			(layer "B.SilkS")
			(hide yes)
			(effects
				(font
					(size 1.27 1.27)
				)
				(justify mirror)
			)
		)
		(property "Value" ""
			(at 0 0 0)
			(layer "B.Fab")
			(effects
				(font
					(size 1.27 1.27)
				)
				(justify mirror)
			)
		)
		(duplicate_pad_numbers_are_jumpers no)
		(fp_line
			(start 0.7874 0.4064)
			(end 0.7874 -0.4064)
			(stroke
				(width 0.1524)
				(type default)
			)
			(layer "B.SilkS")
		)
		(fp_line
			(start 0.7874 -0.4064)
			(end -0.7874 -0.4064)
			(stroke
				(width 0.1524)
				(type default)
			)
			(layer "B.SilkS")
		)
		(fp_line
			(start -0.7874 0.4064)
			(end 0.7874 0.4064)
			(stroke
				(width 0.1524)
				(type default)
			)
			(layer "B.SilkS")
		)
		(fp_line
			(start -0.7874 -0.4064)
			(end -0.7874 0.4064)
			(stroke
				(width 0.1524)
				(type default)
			)
			(layer "B.SilkS")
		)
		(fp_line
			(start 0.67945 0.3048)
			(end 0.67945 -0.305054)
			(stroke
				(width 0.1)
				(type default)
			)
			(layer "B.Fab")
		)
		(fp_line
			(start 0.67945 -0.305054)
			(end 0.12065 -0.305054)
			(stroke
				(width 0.1)
				(type default)
			)
			(layer "B.Fab")
		)
		(fp_line
			(start 0.12065 0.3048)
			(end 0.67945 0.3048)
			(stroke
				(width 0.1)
				(type default)
			)
			(layer "B.Fab")
		)
		(fp_line
			(start 0.12065 0.2794)
			(end 0.12065 0.3048)
			(stroke
				(width 0.1)
				(type default)
			)
			(layer "B.Fab")
		)
		(fp_line
			(start 0.12065 -0.2794)
			(end -0.12065 -0.2794)
			(stroke
				(width 0.1)
				(type default)
			)
			(layer "B.Fab")
		)
		(fp_line
			(start 0.12065 -0.305054)
			(end 0.12065 -0.2794)
			(stroke
				(width 0.1)
				(type default)
			)
			(layer "B.Fab")
		)
		(fp_line
			(start -0.120396 0.3048)
			(end -0.120396 0.2794)
			(stroke
				(width 0.1)
				(type default)
			)
			(layer "B.Fab")
		)
		(fp_line
			(start -0.120396 0.2794)
			(end 0.12065 0.2794)
			(stroke
				(width 0.1)
				(type default)
			)
			(layer "B.Fab")
		)
		(fp_line
			(start -0.12065 -0.2794)
			(end -0.12065 -0.3048)
			(stroke
				(width 0.1)
				(type default)
			)
			(layer "B.Fab")
		)
		(fp_line
			(start -0.12065 -0.3048)
			(end -0.67945 -0.3048)
			(stroke
				(width 0.1)
				(type default)
			)
			(layer "B.Fab")
		)
		(fp_line
			(start -0.67945 0.3048)
			(end -0.120396 0.3048)
			(stroke
				(width 0.1)
				(type default)
			)
			(layer "B.Fab")
		)
		(fp_line
			(start -0.67945 -0.3048)
			(end -0.67945 0.3048)
			(stroke
				(width 0.1)
				(type default)
			)
			(layer "B.Fab")
		)
		(pad "1" smd circle
			(at 0.40005 0)
			(size 0 0)
			(layers "B.Cu" "B.Mask" "B.Paste")
			(net "M_BMC_DDR4_ALERT_N")
		)
		(pad "2" smd circle
			(at -0.40005 0)
			(size 0 0)
			(layers "B.Cu" "B.Mask" "B.Paste")
			(net "P1V2_AUX")
		)
	)
)
